(kicad_pcb
	(version 20260206)
	(generator "pcbnew")
	(generator_version "10.0")
	(general
		(thickness 1.6)
		(legacy_teardrops no)
	)
	(paper "A4")
	(title_block
		(title "baseboard — 13948-1b.1110WZS1818.brd")
		(comment 1 "Honey Badger (Wiwynn) / footprints 668-671 of 2523")
	)
	(layers
		(0 "F.Cu" signal "TOP")
		(4 "In1.Cu" signal "L2GND")
		(6 "In2.Cu" signal "L3")
		(8 "In3.Cu" signal "L4VCC")
		(10 "In4.Cu" signal "L5VCC")
		(12 "In5.Cu" signal "L6")
		(14 "In6.Cu" signal "L7GND")
		(2 "B.Cu" signal "BOTTOM")
		(9 "F.Adhes" user "F.Adhesive")
		(11 "B.Adhes" user "B.Adhesive")
		(13 "F.Paste" user "Package Geometry/Pastemask Top")
		(15 "B.Paste" user "Package Geometry/Pastemask Bottom")
		(5 "F.SilkS" user "Ref Des/Silkscreen Top")
		(7 "B.SilkS" user "Ref Des/Silkscreen Bottom")
		(1 "F.Mask" user "Board Geometry/Soldermask Top")
		(3 "B.Mask" user "Board Geometry/Soldermask Bottom")
		(17 "Dwgs.User" user "User.Drawings")
		(19 "Cmts.User" user "User.Comments")
		(21 "Eco1.User" user "User.Eco1")
		(23 "Eco2.User" user "User.Eco2")
		(25 "Edge.Cuts" user "Board Geometry/Outline")
		(27 "Margin" user)
		(31 "F.CrtYd" user "Package Geometry/Place Bound Top")
		(29 "B.CrtYd" user "Package Geometry/Place Bound Bottom")
		(35 "F.Fab" user "Ref Des/Assembly Top")
		(33 "B.Fab" user "Ref Des/Assembly Bottom")
	)
	(footprint ""
		(layer "F.Cu")
		(at 307.086 -223.139 90)
		(property "Reference" "C331"
			(at 0 0 90)
			(layer "F.SilkS")
			(hide yes)
			(effects
				(font
					(size 1.27 1.27)
				)
			)
		)
		(property "Value" "SCD1U25V2KX-2-GP"
			(at 1.1811 -2.7051 90)
			(unlocked yes)
			(layer "F.Fab")
			(hide yes)
			(effects
				(font
					(size 1.016 1.016)
					(thickness 0.1524)
				)
			)
		)
		(property "Device Type" "C402H22"
			(at 1.1811 -4.2291 90)
			(unlocked yes)
			(layer "F.Fab")
			(hide yes)
			(effects
				(font
					(size 1.016 1.016)
					(thickness 0.1524)
				)
			)
		)
		(duplicate_pad_numbers_are_jumpers no)
		(fp_rect
			(start -0.4318 0.9525)
			(end 0.4318 -0.9525)
			(stroke
				(width 0)
				(type default)
			)
			(fill no)
			(layer "F.CrtYd")
		)
		(fp_rect
			(start -0.4318 0.9525)
			(end 0.4318 -0.9525)
			(stroke
				(width 0)
				(type default)
			)
			(fill no)
			(layer "F.Fab")
		)
		(pad "1" smd custom
			(at 0 -0.4445 90)
			(size 0.1524 0.1524)
			(layers "F.Cu" "F.Mask" "F.Paste")
			(net "P3V3_STBY")
			(options
				(clearance outline)
				(anchor circle)
			)
			(primitives
				(gr_poly
					(pts
						(arc
							(start 0.3048 -0.2032)
							(mid 0.275042 -0.275042)
							(end 0.2032 -0.3048)
						)
						(arc
							(start -0.2032 -0.3048)
							(mid -0.275042 -0.275042)
							(end -0.3048 -0.2032)
						)
						(arc
							(start -0.3048 0.2032)
							(mid -0.275042 0.275042)
							(end -0.2032 0.3048)
						)
						(arc
							(start 0.2032 0.3048)
							(mid 0.275042 0.275042)
							(end 0.3048 0.2032)
						)
					)
					(width 0)
					(fill yes)
				)
			)
		)
		(pad "2" smd custom
			(at 0 0.4445 90)
			(size 0.1524 0.1524)
			(layers "F.Cu" "F.Mask" "F.Paste")
			(net "GND")
			(options
				(clearance outline)
				(anchor circle)
			)
			(primitives
				(gr_poly
					(pts
						(arc
							(start 0.3048 -0.2032)
							(mid 0.275042 -0.275042)
							(end 0.2032 -0.3048)
						)
						(arc
							(start -0.2032 -0.3048)
							(mid -0.275042 -0.275042)
							(end -0.3048 -0.2032)
						)
						(arc
							(start -0.3048 0.2032)
							(mid -0.275042 0.275042)
							(end -0.2032 0.3048)
						)
						(arc
							(start 0.2032 0.3048)
							(mid 0.275042 0.275042)
							(end 0.3048 0.2032)
						)
					)
					(width 0)
					(fill yes)
				)
			)
		)
	)
	(footprint ""
		(layer "F.Cu")
		(at 291.973 -210.058 90)
		(property "Reference" "C180"
			(at 0 0 90)
			(layer "F.SilkS")
			(hide yes)
			(effects
				(font
					(size 1.27 1.27)
				)
			)
		)
		(property "Value" "SC1U16V3KX-5GP"
			(at 0 -2.8194 90)
			(unlocked yes)
			(layer "F.Fab")
			(hide yes)
			(effects
				(font
					(size 1.016 1.016)
					(thickness 0.1524)
				)
			)
		)
		(property "Device Type" "C603H36"
			(at 0 -4.3434 90)
			(unlocked yes)
			(layer "F.Fab")
			(hide yes)
			(effects
				(font
					(size 1.016 1.016)
					(thickness 0.1524)
				)
			)
		)
		(duplicate_pad_numbers_are_jumpers no)
		(fp_line
			(start 0.508 0)
			(end -0.508 0)
			(stroke
				(width 0.2032)
				(type default)
			)
			(layer "F.SilkS")
		)
		(fp_rect
			(start -0.5842 1.3335)
			(end 0.5842 -1.3335)
			(stroke
				(width 0)
				(type default)
			)
			(fill no)
			(layer "F.CrtYd")
		)
		(fp_rect
			(start -0.5842 1.3335)
			(end 0.5842 -1.3335)
			(stroke
				(width 0)
				(type default)
			)
			(fill no)
			(layer "F.Fab")
		)
		(pad "1" smd custom
			(at 0 -0.762 90)
			(size 0.2159 0.2159)
			(layers "F.Cu" "F.Mask" "F.Paste")
			(net "DDR_VREF")
			(options
				(clearance outline)
				(anchor circle)
			)
			(primitives
				(gr_poly
					(pts
						(arc
							(start -0.3302 -0.4318)
							(mid -0.402042 -0.402042)
							(end -0.4318 -0.3302)
						)
						(arc
							(start -0.4318 0.3302)
							(mid -0.402042 0.402042)
							(end -0.3302 0.4318)
						)
						(arc
							(start 0.3302 0.4318)
							(mid 0.402042 0.402042)
							(end 0.4318 0.3302)
						)
						(arc
							(start 0.4318 -0.3302)
							(mid 0.402042 -0.402042)
							(end 0.3302 -0.4318)
						)
					)
					(width 0)
					(fill yes)
				)
			)
		)
		(pad "2" smd custom
			(at 0 0.762 90)
			(size 0.2159 0.2159)
			(layers "F.Cu" "F.Mask" "F.Paste")
			(net "GND")
			(options
				(clearance outline)
				(anchor circle)
			)
			(primitives
				(gr_poly
					(pts
						(arc
							(start -0.3302 -0.4318)
							(mid -0.402042 -0.402042)
							(end -0.4318 -0.3302)
						)
						(arc
							(start -0.4318 0.3302)
							(mid -0.402042 0.402042)
							(end -0.3302 0.4318)
						)
						(arc
							(start 0.3302 0.4318)
							(mid 0.402042 0.402042)
							(end 0.4318 0.3302)
						)
						(arc
							(start 0.4318 -0.3302)
							(mid 0.402042 -0.402042)
							(end 0.3302 -0.4318)
						)
					)
					(width 0)
					(fill yes)
				)
			)
		)
	)
	(footprint ""
		(layer "F.Cu")
		(at 310.896 -186.817 -90)
		(property "Reference" "SR853"
			(at 0 0 270)
			(layer "F.SilkS")
			(hide yes)
			(effects
				(font
					(size 1.27 1.27)
				)
			)
		)
		(property "Value" "4K75R2F-1-GP"
			(at 0.064008 -3.993896 270)
			(unlocked yes)
			(layer "F.Fab")
			(hide yes)
			(effects
				(font
					(size 1.016 1.016)
					(thickness 0.1524)
				)
			)
		)
		(property "Device Type" "R402H16"
			(at 0.064008 -5.517896 270)
			(unlocked yes)
			(layer "F.Fab")
			(hide yes)
			(effects
				(font
					(size 1.016 1.016)
					(thickness 0.1524)
				)
			)
		)
		(duplicate_pad_numbers_are_jumpers no)
		(fp_line
			(start -0.508 -0.9398)
			(end -0.508 0.9398)
			(stroke
				(width 0.1524)
				(type default)
			)
			(layer "F.SilkS")
		)
		(fp_line
			(start 0.508 -0.9398)
			(end -0.508 -0.9398)
			(stroke
				(width 0.1524)
				(type default)
			)
			(layer "F.SilkS")
		)
		(fp_rect
			(start -0.508 0.9398)
			(end 0.508 -0.9398)
			(stroke
				(width 0)
				(type default)
			)
			(fill no)
			(layer "F.CrtYd")
		)
		(fp_rect
			(start -0.508 0.9398)
			(end 0.508 -0.9398)
			(stroke
				(width 0)
				(type default)
			)
			(fill no)
			(layer "F.Fab")
		)
		(pad "1" smd custom
			(at 0 -0.4445 270)
			(size 0.1397 0.1397)
			(layers "F.Cu" "F.Mask" "F.Paste")
			(net "P3V3_STBY")
			(options
				(clearance outline)
				(anchor circle)
			)
			(primitives
				(gr_poly
					(pts
						(arc
							(start -0.1778 -0.2794)
							(mid -0.249642 -0.249642)
							(end -0.2794 -0.1778)
						)
						(arc
							(start -0.2794 0.1778)
							(mid -0.249642 0.249642)
							(end -0.1778 0.2794)
						)
						(arc
							(start 0.1778 0.2794)
							(mid 0.249642 0.249642)
							(end 0.2794 0.1778)
						)
						(arc
							(start 0.2794 -0.1778)
							(mid 0.249642 -0.249642)
							(end 0.1778 -0.2794)
						)
					)
					(width 0)
					(fill yes)
				)
			)
		)
		(pad "2" smd custom
			(at 0 0.4445 270)
			(size 0.1397 0.1397)
			(layers "F.Cu" "F.Mask" "F.Paste")
			(net "BMC_FW_DET_BOARD_VER_2")
			(options
				(clearance outline)
				(anchor circle)
			)
			(primitives
				(gr_poly
					(pts
						(arc
							(start -0.1778 -0.2794)
							(mid -0.249642 -0.249642)
							(end -0.2794 -0.1778)
						)
						(arc
							(start -0.2794 0.1778)
							(mid -0.249642 0.249642)
							(end -0.1778 0.2794)
						)
						(arc
							(start 0.1778 0.2794)
							(mid 0.249642 0.249642)
							(end 0.2794 0.1778)
						)
						(arc
							(start 0.2794 -0.1778)
							(mid 0.249642 -0.249642)
							(end 0.1778 -0.2794)
						)
					)
					(width 0)
					(fill yes)
				)
			)
		)
	)
	(footprint ""
		(layer "F.Cu")
		(at 78.99019 -57.879488 -90)
		(property "Reference" "SC927"
			(at 0 0 270)
			(layer "F.SilkS")
			(hide yes)
			(effects
				(font
					(size 1.27 1.27)
				)
			)
		)
		(property "Value" "SC22U6D3V5MX-2GP"
			(at -0.0762 -6.1214 270)
			(unlocked yes)
			(layer "F.Fab")
			(hide yes)
			(effects
				(font
					(size 1.016 1.016)
					(thickness 0.1524)
				)
			)
		)
		(property "Device Type" "C805H58"
			(at -0.0762 -8.1534 270)
			(unlocked yes)
			(layer "F.Fab")
			(hide yes)
			(effects
				(font
					(size 1.016 1.016)
					(thickness 0.1524)
				)
			)
		)
		(duplicate_pad_numbers_are_jumpers no)
		(fp_line
			(start 0.635 0)
			(end -0.635 0)
			(stroke
				(width 0.508)
				(type default)
			)
			(layer "F.SilkS")
		)
		(fp_rect
			(start -0.9652 1.778)
			(end 0.9652 -1.778)
			(stroke
				(width 0)
				(type default)
			)
			(fill no)
			(layer "F.CrtYd")
		)
		(fp_poly
			(pts
				(xy -0.9652 -1.778) (xy 0.9652 -1.778) (xy 0.9652 1.778) (xy -0.9652 1.778)
			)
			(stroke
				(width 0)
				(type default)
			)
			(fill no)
			(layer "F.Fab")
		)
		(pad "1" smd rect
			(at 0 -0.9652 270)
			(size 1.397 1.143)
			(layers "F.Cu" "F.Mask" "F.Paste")
			(net "SHELL_PLL_VDD")
		)
		(pad "2" smd rect
			(at 0 0.9652 270)
			(size 1.397 1.143)
			(layers "F.Cu" "F.Mask" "F.Paste")
			(net "GND")
		)
	)
)
